FILE_TYPE = CONNECTIVITY;
{Allegro Design Entry HDL 16.6-p007 (v16-6-112F) 10/10/2012}
"PAGE_NUMBER" = 158;
0"NC";
1"P3V3_STBY\g";
2"P3V3_STBY\g";
3"GND\g";
4"GND\g";
5"GND\g";
6"P3V3_STBY\g";
7"P3V3_STBY\g";
8"GND\g";
9"SP2_BMC_CM_UART_RX_R";
10"SP2_BMC_CM_UART_RX";
11"UART_BMC_RXD5";
12"SP1_BMC_HOST_UART_RX";
13"SP2_BMC_CM_UART_RX_R1";
14"UART_MUX_IN_R";
15"FM_UARTSW_MSB_N";
16"FM_UARTSW_LSB_N";
17"SPA_MID_DBG_TX";
18"SP2_BMC_CM_UART_TX_R";
19"FM_UARTSW_LSB_N";
20"UART_MUX_OUT_R";
21"FM_UARTSW_MSB_N";
22"SP2_BMC_CM_UART_TX";
23"UART_BMC_TXD5";
24"SPA_MID_DBG_RX";
25"FM_UARTSW_LSB_R_N";
26"SP1_BMC_HOST_UART_TX";
27"FM_UARTSW_MSB_N";
28"FM_UARTSW_MSB_R_N";
29"SP2_BMC_CM_UART_TX_R1";
30"FM_UARTSW_LSB_N";
%"RES"
"1","(-2650,1525)","0","mstr_discrete","I100";
;
CDS_SEC"1"
LOCATION"R9F24"
TOLERANCE"5%"
MATERIAL"EMPTY"
WATTAGE"1/16W"
VALUE"0.0"
PART_NUMBER"G21497-005"
PACK_TYPE"0402"
ROOM"UART_MUX"
CDS_LOCATION"R9F24"
SEC"1"
SEC_TYPE"0402"
BOM_COST"DEBUG"
CDS_LIB"mstr_discrete";
"B"
$PN"2"10;
"A"
$PN"1"24;
%"LED"
"3","(-5725,3200)","0","mstr_discrete","I130";
;
CDS_SEC"1"
LOCATION"DS9A4"
MATERIAL"IC"
COLOR"GREEN"
PART_NUMBER"D14725-022"
PACK_TYPE"A1LF"
ROOM"UART_MUX"
CDS_LOCATION"DS9A4"
SEC"1"
SEC_TYPE"A1LF"
BOM_COST"DEBUG"
CDS_LIB"mstr_discrete";
"A"
$PN"1"25;
"C"
$PN"2"30;
%"RES"
"1","(-4875,3200)","0","mstr_discrete","I131";
;
CDS_SEC"1"
PART_NUMBER"G21497-028"
LOCATION"R1L43"
TOLERANCE"5%"
WATTAGE"1/16W"
VALUE"330"
MATERIAL"CHIP"
PACK_TYPE"0402"
ROOM"UART_MUX"
SEC_TYPE"0402"
BOM_COST"DEBUG"
SEC"1"
CDS_LOCATION"R1L43"
CDS_LIB"mstr_discrete";
"B"
$PN"2"1;
"A"
$PN"1"25;
%"LED"
"3","(-5725,3600)","0","mstr_discrete","I134";
;
CDS_SEC"1"
PART_NUMBER"D14725-022"
LOCATION"DS9A7"
MATERIAL"IC"
COLOR"GREEN"
PACK_TYPE"A1LF"
ROOM"UART_MUX"
SEC"1"
SEC_TYPE"A1LF"
BOM_COST"DEBUG"
CDS_LOCATION"DS9A7"
CDS_LIB"mstr_discrete";
"A"
$PN"1"28;
"C"
$PN"2"27;
%"P3V3_STBY"
"1","(-4400,3850)","0","mstr_symbols","I135";
;
HDL_POWER"P3V3_STBY"
BODY_TYPE"PLUMBING"
SIZE"1B"
CDS_LIB"mstr_symbols"
VOLTAGE"3.3V";
"G\NAC"1;
%"RES"
"1","(-4875,3600)","0","mstr_discrete","I136";
;
CDS_SEC"1"
PART_NUMBER"G21497-028"
WATTAGE"1/16W"
VALUE"330"
MATERIAL"CHIP"
LOCATION"R1L44"
PACK_TYPE"0402"
TOLERANCE"5%"
SEC"1"
CDS_LIB"mstr_discrete"
SEC_TYPE"0402"
CDS_LOCATION"R1L44"
BOM_COST"DEBUG"
ROOM"UART_MUX";
"B"
$PN"2"1;
"A"
$PN"1"28;
%"RES"
"1","(-3125,3750)","0","mstr_discrete","I148";
;
CDS_SEC"1"
CDS_LOCATION"R9F65"
PACK_TYPE"0402"
VALUE"0.0"
PART_NUMBER"G21497-005"
TOLERANCE"5%"
MATERIAL"CHIP"
LOCATION"R9F65"
WATTAGE"1/16W"
SEC_TYPE"0402"
SEC"1"
ROOM"UART_MUX"
BOM_COST"DEBUG"
CDS_LIB"mstr_discrete";
"B"
$PN"2"18;
"A"
$PN"1"29;
%"RES"
"1","(-1250,850)","0","mstr_discrete","I149";
;
CDS_SEC"1"
LOCATION"R9F68"
PACK_TYPE"0402"
VALUE"0.0"
PART_NUMBER"G21497-005"
WATTAGE"1/16W"
TOLERANCE"5%"
MATERIAL"EMPTY"
SEC_TYPE"0402"
SEC"1"
CDS_LOCATION"R9F68"
CDS_LIB"mstr_discrete"
BOM_COST"DEBUG"
ROOM"UART_MUX";
"B"
$PN"2"10;
"A"
$PN"1"9;
%"RES"
"1","(-1100,1775)","0","mstr_discrete","I150";
;
PART_NUMBER"G21497-005"
VALUE"0.0"
MATERIAL"CHIP"
TOLERANCE"5%"
LOCATION"R9F69"
PACK_TYPE"0402"
WATTAGE"1/16W"
CDS_LOCATION"R9F69"
SEC"1"
SEC_TYPE"0402"
BOM_COST"DEBUG"
ROOM"UART_MUX"
CDS_LIB"mstr_discrete"
CDS_SEC"1";
"B"
$PN"2"13;
"A"
$PN"1"9;
%"RES"
"1","(-3150,2575)","0","mstr_discrete","I152";
;
CDS_SEC"1"
$SEC"1"
CDS_LOCATION"R9F66"
TOLERANCE"5%"
WATTAGE"1/16W"
PART_NUMBER"G21497-005"
PACK_TYPE"0402"
MATERIAL"EMPTY"
LOCATION"R9F66"
VALUE"0.0"
CDS_LIB"mstr_discrete"
BOM_COST"DEBUG"
ROOM"UART_MUX";
"B"
$PN"2"18;
"A"
$PN"1"22;
%"RES"
"2","(-2300,1200)","0","mstr_discrete","I153";
;
CDS_SEC"1"
PACK_TYPE"0402"
MATERIAL"CHIP"
POP"NOPOP"
LOCATION"R9W33"
VALUE"4.75K"
TOLERANCE"1%"
WATTAGE"1/16W"
PART_NUMBER"G21796-072"
ROOM"BMC_MISC"
CDS_LIB"mstr_discrete"
BOM_COST"SM_CONTROLLER"
SEC_TYPE"0402"
SEC"1"
CDS_LOCATION"R9W33";
"A"
$PN"1"2;
"B"
$PN"2"12;
%"RES"
"2","(-2025,1200)","0","mstr_discrete","I154";
;
CDS_SEC"1"
VALUE"4.75K"
LOCATION"R9W34"
MATERIAL"CHIP"
WATTAGE"1/16W"
TOLERANCE"1%"
PACK_TYPE"0402"
POP"NOPOP"
PART_NUMBER"G21796-072"
ROOM"BMC_MISC"
CDS_LIB"mstr_discrete"
BOM_COST"SM_CONTROLLER"
SEC_TYPE"0402"
SEC"1"
CDS_LOCATION"R9W34";
"A"
$PN"1"2;
"B"
$PN"2"11;
%"RES"
"2","(-1750,1200)","0","mstr_discrete","I155";
;
CDS_SEC"1"
TOLERANCE"1%"
LOCATION"R9W35"
VALUE"4.75K"
WATTAGE"1/16W"
MATERIAL"CHIP"
PART_NUMBER"G21796-072"
PACK_TYPE"0402"
POP"NOPOP"
SEC"1"
SEC_TYPE"0402"
BOM_COST"SM_CONTROLLER"
CDS_LIB"mstr_discrete"
ROOM"BMC_MISC"
CDS_LOCATION"R9W35";
"A"
$PN"1"2;
"B"
$PN"2"9;
%"P3V3_STBY"
"1","(-2300,1650)","0","mstr_symbols","I156";
;
VOLTAGE"3.3V"
CDS_LIB"mstr_symbols"
SIZE"1B"
BODY_TYPE"PLUMBING"
HDL_POWER"P3V3_STBY";
"G\NAC"2;
%"CAP_A"
"1","(-1675,2950)","0","dev_discrete","I70";
;
PART_NUMBER"A36096-030"
PACK_TYPE"0402V"
MATERIAL"X7R"
VOLTAGE"16V"
TOLERANCE"10%"
VALUE"0.1UF"
LOCATION"C1T10"
CDS_LIB"dev_discrete"
CDS_LOCATION"C1T10"
BOM_COST"DEBUG"
CDS_SEC"1"
SEC_TYPE"0402V"
SEC"1"
ROOM"UART_MUX";
"B"
$PN"2"3;
"A"
$PN"1"6;
%"GND"
"1","(-1675,2725)","0","mstr_symbols","I72";
;
HDL_POWER"GND"
BODY_TYPE"PLUMBING"
VOLTAGE"0.0V"
SIZE"1B"
CDS_LIB"mstr_symbols";
"A\NAC"3;
%"FSA3357"
"1","(-2175,2575)","2","mstr_analog","I74";
;
CDS_SEC"1"
LOCATION"U9F2"
PART_NUMBER"C63273-001"
MATERIAL"IC"
CDS_LIB"mstr_analog"
SEC_TYPE"SM"
SEC"1"
CDS_LOCATION"U9F2"
ROOM"UART_MUX"
PACK_TYPE"SM"
BOM_COST"DEBUG";
"VCC"
$PN"8"6;
"GND"
$PN"4"4;
"B0"
$PN"1"18;
"B1"
$PN"2"23;
"B2"
$PN"3"26;
"A"
$PN"7"20;
"S2"
$PN"5"21;
"S1"
$PN"6"19;
%"FSA3357"
"1","(-2650,850)","0","mstr_analog","I75";
;
CDS_SEC"1"
MATERIAL"IC"
LOCATION"U9F1"
PART_NUMBER"C63273-001"
PACK_TYPE"SM"
ROOM"UART_MUX"
BOM_COST"DEBUG"
CDS_LOCATION"U9F1"
SEC"1"
SEC_TYPE"SM"
CDS_LIB"mstr_analog";
"VCC"
$PN"8"7;
"GND"
$PN"4"5;
"B0"
$PN"1"9;
"B1"
$PN"2"11;
"B2"
$PN"3"12;
"A"
$PN"7"14;
"S2"
$PN"5"15;
"S1"
$PN"6"16;
%"GND"
"1","(-2625,2125)","0","mstr_symbols","I76";
;
HDL_POWER"GND"
BODY_TYPE"PLUMBING"
SIZE"1B"
VOLTAGE"0.0V"
CDS_LIB"mstr_symbols";
"A\NAC"4;
%"GND"
"1","(-2325,425)","0","mstr_symbols","I77";
;
HDL_POWER"GND"
BODY_TYPE"PLUMBING"
VOLTAGE"0.0V"
SIZE"1B"
CDS_LIB"mstr_symbols";
"A\NAC"5;
%"P3V3_STBY"
"1","(-1850,3150)","0","mstr_symbols","I78";
;
HDL_POWER"P3V3_STBY"
BODY_TYPE"PLUMBING"
VOLTAGE"3.3V"
CDS_LIB"mstr_symbols"
SIZE"1B";
"G\NAC"6;
%"P3V3_STBY"
"1","(-3100,1425)","0","mstr_symbols","I79";
;
HDL_POWER"P3V3_STBY"
BODY_TYPE"PLUMBING"
SIZE"1B"
CDS_LIB"mstr_symbols"
VOLTAGE"3.3V";
"G\NAC"7;
%"RES"
"1","(-3625,900)","0","mstr_discrete","I86";
;
CDS_SEC"1"
WATTAGE"1/16W"
MATERIAL"CHIP"
TOLERANCE"1%"
LOCATION"R9F25"
VALUE"100.0"
PACK_TYPE"0402"
PART_NUMBER"G21796-017"
BOM_COST"DEBUG"
SEC"1"
SEC_TYPE"0402"
ROOM"UART_MUX"
CDS_LIB"mstr_discrete"
CDS_LOCATION"R9F25";
"B"
$PN"2"14;
"A"
$PN"1"24;
%"RES"
"1","(-1325,2625)","0","mstr_discrete","I91";
;
CDS_SEC"1"
VALUE"0.0"
PACK_TYPE"0402"
MATERIAL"CHIP"
WATTAGE"1/16W"
PART_NUMBER"G21497-005"
LOCATION"R9F27"
TOLERANCE"5%"
SEC_TYPE"0402"
SEC"1"
BOM_COST"DEBUG"
CDS_LOCATION"R9F27"
CDS_LIB"mstr_discrete"
ROOM"UART_MUX";
"B"
$PN"2"17;
"A"
$PN"1"20;
%"CAP_A"
"1","(-3475,1200)","0","dev_discrete","I97";
;
VOLTAGE"16V"
PART_NUMBER"A36096-030"
LOCATION"C1T11"
VALUE"0.1UF"
TOLERANCE"10%"
MATERIAL"X7R"
PACK_TYPE"0402V"
ROOM"UART_MUX"
SEC"1"
CDS_LOCATION"C1T11"
CDS_SEC"1"
BOM_COST"DEBUG"
SEC_TYPE"0402V"
CDS_LIB"dev_discrete";
"B"
$PN"2"8;
"A"
$PN"1"7;
%"GND"
"1","(-3475,1000)","0","mstr_symbols","I98";
;
HDL_POWER"GND"
BODY_TYPE"PLUMBING"
CDS_LIB"mstr_symbols"
VOLTAGE"0.0V"
SIZE"1B";
"A\NAC"8;
%"RES"
"1","(-1900,3450)","0","mstr_discrete","I99";
;
CDS_SEC"1"
MATERIAL"EMPTY"
PART_NUMBER"G21497-005"
PACK_TYPE"0402"
LOCATION"R9F26"
WATTAGE"1/16W"
VALUE"0.0"
TOLERANCE"5%"
ROOM"UART_MUX"
BOM_COST"DEBUG"
SEC_TYPE"0402"
SEC"1"
CDS_LOCATION"R9F26"
CDS_LIB"mstr_discrete";
"B"
$PN"2"17;
"A"
$PN"1"22;
END.
